(kicad_pcb
	(version 20260206)
	(generator "pcbnew")
	(generator_version "10.0")
	(general
		(thickness 1.6)
		(legacy_teardrops no)
	)
	(paper "A4")
	(title_block
		(title "timecard-production-celestica-r4006 — R4006-B0001-02_R01.brd")
		(comment 1 "Time Appliance Project (Time Card) / footprints 808-811 of 1113")
	)
	(layers
		(0 "F.Cu" signal "TOP")
		(4 "In1.Cu" signal "L02_GND1")
		(6 "In2.Cu" signal "L03_SIG1")
		(8 "In3.Cu" signal "L04_GND2")
		(10 "In4.Cu" signal "L05_VCC1")
		(12 "In5.Cu" signal "L06_VCC2")
		(14 "In6.Cu" signal "L07_GND3")
		(16 "In7.Cu" signal "L08_SIG2")
		(18 "In8.Cu" signal "L09_GND4")
		(2 "B.Cu" signal "BOTTOM")
		(9 "F.Adhes" user "F.Adhesive")
		(11 "B.Adhes" user "B.Adhesive")
		(13 "F.Paste" user "Package Geometry/Pastemask Top")
		(15 "B.Paste" user "Package Geometry/Pastemask Bottom")
		(5 "F.SilkS" user "Ref Des/Silkscreen Top")
		(7 "B.SilkS" user "Ref Des/Silkscreen Bottom")
		(1 "F.Mask" user "Board Geometry/Soldermask Top")
		(3 "B.Mask" user "Board Geometry/Soldermask Bottom")
		(17 "Dwgs.User" user "User.Drawings")
		(19 "Cmts.User" user "User.Comments")
		(21 "Eco1.User" user "User.Eco1")
		(23 "Eco2.User" user "User.Eco2")
		(25 "Edge.Cuts" user "Board Geometry/Outline")
		(27 "Margin" user)
		(31 "F.CrtYd" user "Package Geometry/Place Bound Top")
		(29 "B.CrtYd" user "Package Geometry/Place Bound Bottom")
		(35 "F.Fab" user "Ref Des/Assembly Top")
		(33 "B.Fab" user "Ref Des/Assembly Bottom")
	)
	(footprint ""
		(layer "B.Cu")
		(at 73.914 -58.928 90)
		(property "Reference" "R44"
			(at 2.54 6.81863 270)
			(unlocked yes)
			(layer "B.SilkS")
			(effects
				(font
					(size 0.7874 0.5842)
					(thickness 0.1524)
				)
				(justify mirror)
			)
		)
		(property "Value" "VAL*"
			(at -0.02032 2.13233 90)
			(unlocked yes)
			(layer "B.Fab")
			(hide yes)
			(effects
				(font
					(size 0.7874 0.5842)
					(thickness 0.1524)
				)
				(justify mirror)
			)
		)
		(property "Tolerance" "TOL*"
			(at -0.044704 3.05435 90)
			(unlocked yes)
			(layer "Cmts.User")
			(hide yes)
			(effects
				(font
					(size 0.7874 0.5842)
					(thickness 0.1524)
				)
				(justify mirror)
			)
		)
		(property "User Part Number" "PARTNUM*"
			(at -0.02032 4.024884 90)
			(unlocked yes)
			(layer "Cmts.User")
			(hide yes)
			(effects
				(font
					(size 0.7874 0.5842)
					(thickness 0.1524)
				)
				(justify mirror)
			)
		)
		(property "Device Type" "RESISTOR-G155-14701-01,4.7KOHMA"
			(at -0.008382 1.210564 90)
			(unlocked yes)
			(layer "B.Fab")
			(hide yes)
			(effects
				(font
					(size 0.7874 0.5842)
					(thickness 0.1524)
				)
				(justify mirror)
			)
		)
		(duplicate_pad_numbers_are_jumpers no)
		(fp_line
			(start 1.143 -0.5588)
			(end 1.143 0.5588)
			(stroke
				(width 0.1)
				(type default)
			)
			(layer "B.SilkS")
		)
		(fp_line
			(start -1.143 -0.5588)
			(end 1.143 -0.5588)
			(stroke
				(width 0.1)
				(type default)
			)
			(layer "B.SilkS")
		)
		(fp_line
			(start 1.143 0.5588)
			(end -1.143 0.5588)
			(stroke
				(width 0.1)
				(type default)
			)
			(layer "B.SilkS")
		)
		(fp_line
			(start -1.143 0.5588)
			(end -1.143 -0.5588)
			(stroke
				(width 0.1)
				(type default)
			)
			(layer "B.SilkS")
		)
		(fp_rect
			(start 1.143 0.5588)
			(end -1.143 -0.5588)
			(stroke
				(width 0)
				(type default)
			)
			(fill no)
			(layer "B.CrtYd")
		)
		(fp_line
			(start 0.508 -0.3048)
			(end 0.508 0.3048)
			(stroke
				(width 0.1)
				(type default)
			)
			(layer "B.Fab")
		)
		(fp_line
			(start -0.508 -0.3048)
			(end 0.508 -0.3048)
			(stroke
				(width 0.1)
				(type default)
			)
			(layer "B.Fab")
		)
		(fp_line
			(start 0.508 0.3048)
			(end -0.508 0.3048)
			(stroke
				(width 0.1)
				(type default)
			)
			(layer "B.Fab")
		)
		(fp_line
			(start -0.508 0.3048)
			(end -0.508 -0.3048)
			(stroke
				(width 0.1)
				(type default)
			)
			(layer "B.Fab")
		)
		(pad "1" smd rect
			(at 0.5334 0 270)
			(size 0.7112 0.6096)
			(layers "B.Cu" "B.Mask" "B.Paste")
			(net "XP5R0V_MAC")
		)
		(pad "2" smd rect
			(at -0.5334 0 270)
			(size 0.7112 0.6096)
			(layers "B.Cu" "B.Mask" "B.Paste")
			(net "UNNAMED_527_POWERMOS3PNCHV1_I23")
		)
		(zone
			(layer "B.Cu")
			(hatch none 0.5)
			(connect_pads
				(clearance 0)
			)
			(min_thickness 0.25)
			(keepout
				(tracks allowed)
				(vias not_allowed)
				(pads allowed)
				(copperpour not_allowed)
				(footprints allowed)
			)
			(placement
				(enabled no)
				(sheetname "")
			)
			(fill
				(thermal_gap 0.5)
				(thermal_bridge_width 0.5)
				(island_removal_mode 0)
			)
			(polygon
				(pts
					(xy 74.2188 -59.0042) (xy 73.6092 -59.0042) (xy 73.6092 -58.8518) (xy 74.2188 -58.8518)
				)
			)
		)
		(zone
			(layer "B.Cu")
			(hatch none 0.5)
			(connect_pads
				(clearance 0)
			)
			(min_thickness 0.25)
			(keepout
				(tracks not_allowed)
				(vias allowed)
				(pads allowed)
				(copperpour not_allowed)
				(footprints allowed)
			)
			(placement
				(enabled no)
				(sheetname "")
			)
			(fill
				(thermal_gap 0.5)
				(thermal_bridge_width 0.5)
				(island_removal_mode 0)
			)
			(polygon
				(pts
					(xy 74.2188 -59.0042) (xy 73.6092 -59.0042) (xy 73.6092 -58.8518) (xy 74.2188 -58.8518)
				)
			)
		)
	)
	(footprint ""
		(layer "B.Cu")
		(at 33.528 -90.805 90)
		(property "Reference" "L22"
			(at 3.175 -0.03937 270)
			(unlocked yes)
			(layer "B.SilkS")
			(effects
				(font
					(size 0.7874 0.5842)
					(thickness 0.1524)
				)
				(justify mirror)
			)
		)
		(property "Value" "VAL*"
			(at -0.014732 2.526538 90)
			(unlocked yes)
			(layer "B.Fab")
			(hide yes)
			(effects
				(font
					(size 0.7874 0.5842)
					(thickness 0.000001)
				)
				(justify mirror)
			)
		)
		(property "Tolerance" "TOL*"
			(at -0.014732 3.503676 90)
			(unlocked yes)
			(layer "Cmts.User")
			(hide yes)
			(effects
				(font
					(size 0.7874 0.5842)
					(thickness 0.000001)
				)
				(justify mirror)
			)
		)
		(property "User Part Number" "PARTNUM*"
			(at -0.02794 4.480814 90)
			(unlocked yes)
			(layer "Cmts.User")
			(hide yes)
			(effects
				(font
					(size 0.7874 0.5842)
					(thickness 0.000001)
				)
				(justify mirror)
			)
		)
		(property "Device Type" "FERRITEBEAD-G191-10097-01,600OA"
			(at -0.014732 1.600708 90)
			(unlocked yes)
			(layer "B.Fab")
			(hide yes)
			(effects
				(font
					(size 0.7874 0.5842)
					(thickness 0.000001)
				)
				(justify mirror)
			)
		)
		(duplicate_pad_numbers_are_jumpers no)
		(fp_line
			(start 1.3208 -0.7112)
			(end -1.3208 -0.7112)
			(stroke
				(width 0.1)
				(type default)
			)
			(layer "B.SilkS")
		)
		(fp_line
			(start -1.3208 -0.7112)
			(end -1.3208 0.7112)
			(stroke
				(width 0.1)
				(type default)
			)
			(layer "B.SilkS")
		)
		(fp_line
			(start 1.3208 0.7112)
			(end 1.3208 -0.7112)
			(stroke
				(width 0.1)
				(type default)
			)
			(layer "B.SilkS")
		)
		(fp_line
			(start -1.3208 0.7112)
			(end 1.3208 0.7112)
			(stroke
				(width 0.1)
				(type default)
			)
			(layer "B.SilkS")
		)
		(fp_rect
			(start 1.3208 0.7112)
			(end -1.3208 -0.7112)
			(stroke
				(width 0)
				(type default)
			)
			(fill no)
			(layer "B.CrtYd")
		)
		(fp_line
			(start 0.8128 -0.4572)
			(end -0.8128 -0.4572)
			(stroke
				(width 0.1)
				(type default)
			)
			(layer "B.Fab")
		)
		(fp_line
			(start -0.8128 -0.4572)
			(end -0.8128 0.4572)
			(stroke
				(width 0.1)
				(type default)
			)
			(layer "B.Fab")
		)
		(fp_line
			(start 0.8128 0.4572)
			(end 0.8128 -0.4572)
			(stroke
				(width 0.1)
				(type default)
			)
			(layer "B.Fab")
		)
		(fp_line
			(start -0.8128 0.4572)
			(end 0.8128 0.4572)
			(stroke
				(width 0.1)
				(type default)
			)
			(layer "B.Fab")
		)
		(pad "1" smd rect
			(at 0.6858 0 270)
			(size 0.762 0.8636)
			(layers "B.Cu" "B.Mask" "B.Paste")
			(net "XP3R3V_FT4232")
		)
		(pad "2" smd rect
			(at -0.6858 0 270)
			(size 0.762 0.8636)
			(layers "B.Cu" "B.Mask" "B.Paste")
			(net "XP3R3V_VPHY")
		)
		(zone
			(layer "B.Cu")
			(hatch none 0.5)
			(connect_pads
				(clearance 0)
			)
			(min_thickness 0.25)
			(keepout
				(tracks allowed)
				(vias not_allowed)
				(pads allowed)
				(copperpour not_allowed)
				(footprints allowed)
			)
			(placement
				(enabled no)
				(sheetname "")
			)
			(fill
				(thermal_gap 0.5)
				(thermal_bridge_width 0.5)
				(island_removal_mode 0)
			)
			(polygon
				(pts
					(xy 33.9852 -90.9574) (xy 33.0708 -90.9574) (xy 33.0708 -90.6526) (xy 33.9852 -90.6526)
				)
			)
		)
		(zone
			(layer "B.Cu")
			(hatch none 0.5)
			(connect_pads
				(clearance 0)
			)
			(min_thickness 0.25)
			(keepout
				(tracks not_allowed)
				(vias allowed)
				(pads allowed)
				(copperpour not_allowed)
				(footprints allowed)
			)
			(placement
				(enabled no)
				(sheetname "")
			)
			(fill
				(thermal_gap 0.5)
				(thermal_bridge_width 0.5)
				(island_removal_mode 0)
			)
			(polygon
				(pts
					(xy 33.9852 -90.9574) (xy 33.0708 -90.9574) (xy 33.0708 -90.6526) (xy 33.9852 -90.6526)
				)
			)
		)
	)
	(footprint ""
		(layer "B.Cu")
		(at 116.346986 -35.82289)
		(property "Reference" "C127"
			(at 0.239014 -0.97536 0)
			(unlocked yes)
			(layer "B.SilkS")
			(effects
				(font
					(size 0.635 0.4064)
					(thickness 0.1524)
				)
				(justify mirror)
			)
		)
		(property "Value" "VAL*"
			(at 0 3.718306 0)
			(unlocked yes)
			(layer "B.Fab")
			(hide yes)
			(effects
				(font
					(size 0.7874 0.5842)
					(thickness 0.127)
				)
				(justify mirror)
			)
		)
		(property "Device Type" "CAPACITOR-G105-0B104-CK,0.1UF,A"
			(at 0 1.432306 0)
			(unlocked yes)
			(layer "B.Fab")
			(hide yes)
			(effects
				(font
					(size 0.7874 0.5842)
					(thickness 0.127)
				)
				(justify mirror)
			)
		)
		(property "User Part Number" "PARTNUM*"
			(at 0 2.575306 0)
			(unlocked yes)
			(layer "Cmts.User")
			(hide yes)
			(effects
				(font
					(size 0.7874 0.5842)
					(thickness 0.127)
				)
				(justify mirror)
			)
		)
		(property "Tolerance" "TOL*"
			(at 0 4.861306 0)
			(unlocked yes)
			(layer "Cmts.User")
			(hide yes)
			(effects
				(font
					(size 0.7874 0.5842)
					(thickness 0.127)
				)
				(justify mirror)
			)
		)
		(duplicate_pad_numbers_are_jumpers no)
		(fp_line
			(start -0.970026 -0.4699)
			(end -0.970026 0.4699)
			(stroke
				(width 0.1)
				(type default)
			)
			(layer "B.SilkS")
		)
		(fp_line
			(start -0.970026 0.4699)
			(end 0.970026 0.4699)
			(stroke
				(width 0.1)
				(type default)
			)
			(layer "B.SilkS")
		)
		(fp_line
			(start 0.970026 -0.4699)
			(end -0.970026 -0.4699)
			(stroke
				(width 0.1)
				(type default)
			)
			(layer "B.SilkS")
		)
		(fp_line
			(start 0.970026 0.4699)
			(end 0.970026 -0.4699)
			(stroke
				(width 0.1)
				(type default)
			)
			(layer "B.SilkS")
		)
		(fp_poly
			(pts
				(xy 0.970026 0.4699) (xy -0.970026 0.4699) (xy -0.970026 -0.4699) (xy 0.970026 -0.4699)
			)
			(stroke
				(width 0)
				(type default)
			)
			(fill no)
			(layer "B.CrtYd")
		)
		(fp_line
			(start -0.508 -0.3048)
			(end -0.508 0.3048)
			(stroke
				(width 0.1)
				(type default)
			)
			(layer "B.Fab")
		)
		(fp_line
			(start -0.508 0.3048)
			(end 0.508 0.3048)
			(stroke
				(width 0.1)
				(type default)
			)
			(layer "B.Fab")
		)
		(fp_line
			(start 0.508 -0.3048)
			(end -0.508 -0.3048)
			(stroke
				(width 0.1)
				(type default)
			)
			(layer "B.Fab")
		)
		(fp_line
			(start 0.508 0.3048)
			(end 0.508 -0.3048)
			(stroke
				(width 0.1)
				(type default)
			)
			(layer "B.Fab")
		)
		(pad "1" smd circle
			(at 0.500126 0 180)
			(size 0.635 0.635)
			(layers "B.Cu" "B.Mask" "B.Paste")
			(net "XP2R5V_FPGA")
		)
		(pad "2" smd circle
			(at -0.500126 0 180)
			(size 0.635 0.635)
			(layers "B.Cu" "B.Mask" "B.Paste")
			(net "SG")
		)
	)
	(footprint ""
		(layer "B.Cu")
		(at 112.84712 -36.323016 90)
		(property "Reference" "C135"
			(at -2.287016 -0.10287 270)
			(unlocked yes)
			(layer "B.SilkS")
			(effects
				(font
					(size 0.635 0.4064)
					(thickness 0.1524)
				)
				(justify mirror)
			)
		)
		(property "Value" "VAL*"
			(at 0 3.718306 90)
			(unlocked yes)
			(layer "B.Fab")
			(hide yes)
			(effects
				(font
					(size 0.7874 0.5842)
					(thickness 0.127)
				)
				(justify mirror)
			)
		)
		(property "Tolerance" "TOL*"
			(at 0 4.861306 90)
			(unlocked yes)
			(layer "Cmts.User")
			(hide yes)
			(effects
				(font
					(size 0.7874 0.5842)
					(thickness 0.127)
				)
				(justify mirror)
			)
		)
		(property "User Part Number" "PARTNUM*"
			(at 0 2.575306 90)
			(unlocked yes)
			(layer "Cmts.User")
			(hide yes)
			(effects
				(font
					(size 0.7874 0.5842)
					(thickness 0.127)
				)
				(justify mirror)
			)
		)
		(property "Device Type" "CAPACITOR-G105-0B104-CK,0.1UF,A"
			(at 0 1.432306 90)
			(unlocked yes)
			(layer "B.Fab")
			(hide yes)
			(effects
				(font
					(size 0.7874 0.5842)
					(thickness 0.127)
				)
				(justify mirror)
			)
		)
		(duplicate_pad_numbers_are_jumpers no)
		(fp_line
			(start 0.970026 -0.4699)
			(end -0.970026 -0.4699)
			(stroke
				(width 0.1)
				(type default)
			)
			(layer "B.SilkS")
		)
		(fp_line
			(start -0.970026 -0.4699)
			(end -0.970026 0.4699)
			(stroke
				(width 0.1)
				(type default)
			)
			(layer "B.SilkS")
		)
		(fp_line
			(start 0.970026 0.4699)
			(end 0.970026 -0.4699)
			(stroke
				(width 0.1)
				(type default)
			)
			(layer "B.SilkS")
		)
		(fp_line
			(start -0.970026 0.4699)
			(end 0.970026 0.4699)
			(stroke
				(width 0.1)
				(type default)
			)
			(layer "B.SilkS")
		)
		(fp_poly
			(pts
				(xy 0.970026 0.4699) (xy -0.970026 0.4699) (xy -0.970026 -0.4699) (xy 0.970026 -0.4699)
			)
			(stroke
				(width 0)
				(type default)
			)
			(fill no)
			(layer "B.CrtYd")
		)
		(fp_line
			(start 0.508 -0.3048)
			(end -0.508 -0.3048)
			(stroke
				(width 0.1)
				(type default)
			)
			(layer "B.Fab")
		)
		(fp_line
			(start -0.508 -0.3048)
			(end -0.508 0.3048)
			(stroke
				(width 0.1)
				(type default)
			)
			(layer "B.Fab")
		)
		(fp_line
			(start 0.508 0.3048)
			(end 0.508 -0.3048)
			(stroke
				(width 0.1)
				(type default)
			)
			(layer "B.Fab")
		)
		(fp_line
			(start -0.508 0.3048)
			(end 0.508 0.3048)
			(stroke
				(width 0.1)
				(type default)
			)
			(layer "B.Fab")
		)
		(pad "1" smd circle
			(at 0.500126 0 270)
			(size 0.635 0.635)
			(layers "B.Cu" "B.Mask" "B.Paste")
			(net "XP2R5V_FPGA")
		)
		(pad "2" smd circle
			(at -0.500126 0 270)
			(size 0.635 0.635)
			(layers "B.Cu" "B.Mask" "B.Paste")
			(net "SG")
		)
	)
)
